# BASEBOARD_FAB2 (Tioga Pass) — schematic netlist excerpt (pin names and nets, part order shuffled) for the footprints in the layout excerpt that follows; sources: Cadence DE-HDL packaged netlist, KiCad conversion of Wiwynn_Tioga_Pass_MB.brd

R1W34  RES  0.0 5% CHIP  pkg 0402  page 176 : A = SMB_DEBUG_STBY_LVC3_SDA_R1 ; B = SMB_DEBUG_STBY_LVC3_SDA
C9P14  CAP  0.033UF 50V 10% X7R  pkg 0603LF  page 199 : A = A_HSC_TIMER ; B = AGND_HSC
C6U10  CAP  10UF 16V 10% X7R  pkg 0805  page 197 : A = P12V_NVDIMM_ABC ; B = GND

(kicad_pcb
	(version 20260206)
	(generator "pcbnew")
	(generator_version "10.0")
	(general
		(thickness 1.6)
		(legacy_teardrops no)
	)
	(paper "A4")
	(title_block
		(title "Wiwynn_Tioga_Pass_MB.brd")
		(comment 1 "Tioga Pass / footprints 3649-3651 of 4770")
	)
	(layers
		(0 "F.Cu" signal "TOP")
		(4 "In1.Cu" signal "L2GND")
		(6 "In2.Cu" signal "L3")
		(8 "In3.Cu" signal "L4GND")
		(10 "In4.Cu" signal "L5")
		(12 "In5.Cu" signal "L6GND")
		(14 "In6.Cu" signal "L7VCC")
		(16 "In7.Cu" signal "L8VCC")
		(18 "In8.Cu" signal "L9GND")
		(20 "In9.Cu" signal "L10")
		(22 "In10.Cu" signal "L11GND")
		(24 "In11.Cu" signal "L12")
		(26 "In12.Cu" signal "L13GND")
		(2 "B.Cu" signal "BOTTOM")
		(9 "F.Adhes" user "F.Adhesive")
		(11 "B.Adhes" user "B.Adhesive")
		(13 "F.Paste" user "Package Geometry/Pastemask Top")
		(15 "B.Paste" user "Package Geometry/Pastemask Bottom")
		(5 "F.SilkS" user "Ref Des/Silkscreen Top")
		(7 "B.SilkS" user "Ref Des/Silkscreen Bottom")
		(1 "F.Mask" user "Board Geometry/Soldermask Top")
		(3 "B.Mask" user "Board Geometry/Soldermask Bottom")
		(17 "Dwgs.User" user "User.Drawings")
		(19 "Cmts.User" user "User.Comments")
		(21 "Eco1.User" user "User.Eco1")
		(23 "Eco2.User" user "User.Eco2")
		(25 "Edge.Cuts" user "Board Geometry/Outline")
		(27 "Margin" user)
		(31 "F.CrtYd" user "Package Geometry/Place Bound Top")
		(29 "B.CrtYd" user "Package Geometry/Place Bound Bottom")
		(35 "F.Fab" user "Ref Des/Assembly Top")
		(33 "B.Fab" user "Ref Des/Assembly Bottom")
	)
	(footprint ""
		(layer "B.Cu")
		(at 22.606 -75.946 90)
		(property "Reference" "C9P14"
			(at 0 0 90)
			(layer "B.SilkS")
			(hide yes)
			(effects
				(font
					(size 1.27 1.27)
				)
				(justify mirror)
			)
		)
		(property "Value" ""
			(at 0 0 90)
			(layer "B.Fab")
			(effects
				(font
					(size 1.27 1.27)
				)
				(justify mirror)
			)
		)
		(duplicate_pad_numbers_are_jumpers no)
		(fp_rect
			(start 0.4953 1.6002)
			(end -0.4953 -0.2032)
			(stroke
				(width 0)
				(type default)
			)
			(fill no)
			(layer "B.CrtYd")
		)
		(fp_line
			(start 0.4953 -0.2032)
			(end -0.4953 -0.2032)
			(stroke
				(width 0.1)
				(type default)
			)
			(layer "B.Fab")
		)
		(fp_line
			(start -0.4953 -0.2032)
			(end -0.4953 1.6002)
			(stroke
				(width 0.1)
				(type default)
			)
			(layer "B.Fab")
		)
		(fp_line
			(start 0.4953 1.6002)
			(end 0.4953 -0.2032)
			(stroke
				(width 0.1)
				(type default)
			)
			(layer "B.Fab")
		)
		(fp_line
			(start -0.4953 1.6002)
			(end 0.4953 1.6002)
			(stroke
				(width 0.1)
				(type default)
			)
			(layer "B.Fab")
		)
		(pad "1" smd rect
			(at 0 0 270)
			(size 0.762 0.889)
			(layers "B.Cu" "B.Mask" "B.Paste")
			(net "A_HSC_TIMER")
		)
		(pad "2" smd rect
			(at 0 1.397 270)
			(size 0.762 0.889)
			(layers "B.Cu" "B.Mask" "B.Paste")
			(net "AGND_HSC")
		)
		(zone
			(layer "B.Cu")
			(hatch none 0.5)
			(connect_pads
				(clearance 0)
			)
			(min_thickness 0.25)
			(keepout
				(tracks not_allowed)
				(vias allowed)
				(pads allowed)
				(copperpour not_allowed)
				(footprints allowed)
			)
			(placement
				(enabled no)
				(sheetname "")
			)
			(fill
				(thermal_gap 0.5)
				(thermal_bridge_width 0.5)
				(island_removal_mode 0)
			)
			(polygon
				(pts
					(xy 23.5585 -76.327) (xy 23.0505 -76.327) (xy 23.0505 -75.565) (xy 23.5585 -75.565)
				)
			)
		)
	)
	(footprint ""
		(layer "B.Cu")
		(at 193.092832 -8.122412 -90)
		(property "Reference" "C6U10"
			(at 0 0 90)
			(layer "B.SilkS")
			(hide yes)
			(effects
				(font
					(size 1.27 1.27)
				)
				(justify mirror)
			)
		)
		(property "Value" ""
			(at 0 0 90)
			(layer "B.Fab")
			(effects
				(font
					(size 1.27 1.27)
				)
				(justify mirror)
			)
		)
		(duplicate_pad_numbers_are_jumpers no)
		(fp_rect
			(start 0.7239 1.9939)
			(end -0.7239 -0.2159)
			(stroke
				(width 0)
				(type default)
			)
			(fill no)
			(layer "B.CrtYd")
		)
		(fp_line
			(start -0.7239 1.9939)
			(end -0.7239 -0.2159)
			(stroke
				(width 0.1)
				(type default)
			)
			(layer "B.Fab")
		)
		(fp_line
			(start 0.7239 1.9939)
			(end -0.7239 1.9939)
			(stroke
				(width 0.1)
				(type default)
			)
			(layer "B.Fab")
		)
		(fp_line
			(start -0.7239 -0.2159)
			(end 0.7239 -0.2159)
			(stroke
				(width 0.1)
				(type default)
			)
			(layer "B.Fab")
		)
		(fp_line
			(start 0.7239 -0.2159)
			(end 0.7239 1.9939)
			(stroke
				(width 0.1)
				(type default)
			)
			(layer "B.Fab")
		)
		(pad "1" smd rect
			(at 0 0 90)
			(size 1.27 1.016)
			(layers "B.Cu" "B.Mask" "B.Paste")
			(net "P12V_NVDIMM_ABC")
		)
		(pad "2" smd rect
			(at 0 1.778 90)
			(size 1.27 1.016)
			(layers "B.Cu" "B.Mask" "B.Paste")
			(net "GND")
		)
		(zone
			(layer "B.Cu")
			(hatch none 0.5)
			(connect_pads
				(clearance 0)
			)
			(min_thickness 0.25)
			(keepout
				(tracks not_allowed)
				(vias allowed)
				(pads allowed)
				(copperpour not_allowed)
				(footprints allowed)
			)
			(placement
				(enabled no)
				(sheetname "")
			)
			(fill
				(thermal_gap 0.5)
				(thermal_bridge_width 0.5)
				(island_removal_mode 0)
			)
			(polygon
				(pts
					(xy 191.822832 -7.487412) (xy 192.584832 -7.487412) (xy 192.584832 -8.757412) (xy 191.822832 -8.757412)
				)
			)
		)
	)
	(footprint ""
		(layer "B.Cu")
		(at 474.814138 -127.242316 -90)
		(property "Reference" "R1W34"
			(at 0.8382 -0.67818 270)
			(unlocked yes)
			(layer "B.SilkS")
			(effects
				(font
					(size 0.4064 0.254)
					(thickness 0.1524)
				)
				(justify left mirror)
			)
		)
		(property "Value" ""
			(at 0 0 90)
			(layer "B.Fab")
			(effects
				(font
					(size 1.27 1.27)
				)
				(justify mirror)
			)
		)
		(duplicate_pad_numbers_are_jumpers no)
		(fp_poly
			(pts
				(xy 0.2794 -0.1016) (xy -0.2794 -0.1016) (xy -0.2794 0.9906) (xy 0.2794 0.9906)
			)
			(stroke
				(width 0)
				(type default)
			)
			(fill no)
			(layer "B.CrtYd")
		)
		(fp_line
			(start -0.2794 0.9906)
			(end -0.2794 -0.1016)
			(stroke
				(width 0.1)
				(type default)
			)
			(layer "B.Fab")
		)
		(fp_line
			(start 0.2794 0.9906)
			(end -0.2794 0.9906)
			(stroke
				(width 0.1)
				(type default)
			)
			(layer "B.Fab")
		)
		(fp_line
			(start -0.2794 -0.1016)
			(end 0.2794 -0.1016)
			(stroke
				(width 0.1)
				(type default)
			)
			(layer "B.Fab")
		)
		(fp_line
			(start 0.2794 -0.1016)
			(end 0.2794 0.9906)
			(stroke
				(width 0.1)
				(type default)
			)
			(layer "B.Fab")
		)
		(pad "1" smd rect
			(at 0 0 90)
			(size 0.508 0.508)
			(layers "B.Cu" "B.Mask" "B.Paste")
			(net "SMB_DEBUG_STBY_LVC3_SDA_R1")
		)
		(pad "2" smd rect
			(at 0 0.889 90)
			(size 0.508 0.508)
			(layers "B.Cu" "B.Mask" "B.Paste")
			(net "SMB_DEBUG_STBY_LVC3_SDA")
		)
		(zone
			(layer "B.Cu")
			(hatch none 0.5)
			(connect_pads
				(clearance 0)
			)
			(min_thickness 0.25)
			(keepout
				(tracks not_allowed)
				(vias allowed)
				(pads allowed)
				(copperpour not_allowed)
				(footprints allowed)
			)
			(placement
				(enabled no)
				(sheetname "")
			)
			(fill
				(thermal_gap 0.5)
				(thermal_bridge_width 0.5)
				(island_removal_mode 0)
			)
			(polygon
				(pts
					(xy 474.179138 -126.988316) (xy 474.179138 -127.496316) (xy 474.560138 -127.496316) (xy 474.560138 -126.988316)
				)
			)
		)
		(zone
			(layer "B.Cu")
			(hatch none 0.5)
			(connect_pads
				(clearance 0)
			)
			(min_thickness 0.25)
			(keepout
				(tracks allowed)
				(vias not_allowed)
				(pads allowed)
				(copperpour not_allowed)
				(footprints allowed)
			)
			(placement
				(enabled no)
				(sheetname "")
			)
			(fill
				(thermal_gap 0.5)
				(thermal_bridge_width 0.5)
				(island_removal_mode 0)
			)
			(polygon
				(pts
					(xy 474.560138 -126.988316) (xy 474.560138 -127.496316) (xy 474.179138 -127.496316) (xy 474.179138 -126.988316)
				)
			)
		)
	)
)
